# S9S_MB_2U (Grand Teton) — schematic netlist excerpt (pin names and nets, part order shuffled) for the footprints in the layout excerpt that follows; sources: Cadence DE-HDL packaged netlist, KiCad conversion of 03242023_DA0F0TMBIJ0_F0T_Motherboard_J_brd_V01_OCP.brd

PC2361  Q_CAP  0.1UF 25V 10% EMPTY  pkg 0402  page 266 : A = PVCCIN_CPU0_VCC ; B = GND
C1317  Q_CAP  0.1UF 25V 10% X7R  pkg 0402  page 244 : A = P3V3_AUX ; B = GND

(kicad_pcb
	(version 20260206)
	(generator "pcbnew")
	(generator_version "10.0")
	(general
		(thickness 1.6)
		(legacy_teardrops no)
	)
	(paper "A4")
	(title_block
		(title "03242023_DA0F0TMBIJ0_F0T_Motherboard_J_brd_V01_OCP.brd")
		(comment 1 "Grand Teton / footprints 724-725 of 6105")
	)
	(layers
		(0 "F.Cu" signal "TOP")
		(4 "In1.Cu" signal "GND")
		(6 "In2.Cu" signal "IN1")
		(8 "In3.Cu" signal "GND1")
		(10 "In4.Cu" signal "IN2")
		(12 "In5.Cu" signal "GND2")
		(14 "In6.Cu" signal "IN3")
		(16 "In7.Cu" signal "GND3")
		(18 "In8.Cu" signal "VCC")
		(20 "In9.Cu" signal "VCC1")
		(22 "In10.Cu" signal "GND4")
		(24 "In11.Cu" signal "IN4")
		(26 "In12.Cu" signal "GND5")
		(28 "In13.Cu" signal "IN5")
		(30 "In14.Cu" signal "GND6")
		(32 "In15.Cu" signal "IN6")
		(34 "In16.Cu" signal "GND7")
		(2 "B.Cu" signal "BOTTOM")
		(9 "F.Adhes" user "F.Adhesive")
		(11 "B.Adhes" user "B.Adhesive")
		(13 "F.Paste" user "Package Geometry/Pastemask Top")
		(15 "B.Paste" user "Package Geometry/Pastemask Bottom")
		(5 "F.SilkS" user "Ref Des/Silkscreen Top")
		(7 "B.SilkS" user "Ref Des/Silkscreen Bottom")
		(1 "F.Mask" user "Board Geometry/Soldermask Top")
		(3 "B.Mask" user "Board Geometry/Soldermask Bottom")
		(17 "Dwgs.User" user "User.Drawings")
		(19 "Cmts.User" user "User.Comments")
		(21 "Eco1.User" user "User.Eco1")
		(23 "Eco2.User" user "User.Eco2")
		(25 "Edge.Cuts" user "Board Geometry/Outline")
		(27 "Margin" user)
		(31 "F.CrtYd" user "Package Geometry/Place Bound Top")
		(29 "B.CrtYd" user "Package Geometry/Place Bound Bottom")
		(35 "F.Fab" user "Ref Des/Assembly Top")
		(33 "B.Fab" user "Ref Des/Assembly Bottom")
	)
	(footprint ""
		(layer "F.Cu")
		(at 362.65358 -363.5121)
		(property "Reference" "PC2361"
			(at 0 0 0)
			(layer "F.SilkS")
			(hide yes)
			(effects
				(font
					(size 1.27 1.27)
				)
			)
		)
		(property "Value" ""
			(at 0 0 0)
			(layer "F.Fab")
			(effects
				(font
					(size 1.27 1.27)
				)
			)
		)
		(duplicate_pad_numbers_are_jumpers no)
		(fp_line
			(start -0.7874 -0.4064)
			(end 0.7874 -0.4064)
			(stroke
				(width 0.1524)
				(type default)
			)
			(layer "F.SilkS")
		)
		(fp_line
			(start -0.7874 0.4064)
			(end -0.7874 -0.4064)
			(stroke
				(width 0.1524)
				(type default)
			)
			(layer "F.SilkS")
		)
		(fp_line
			(start 0.7874 -0.4064)
			(end 0.7874 0.4064)
			(stroke
				(width 0.1524)
				(type default)
			)
			(layer "F.SilkS")
		)
		(fp_line
			(start 0.7874 0.4064)
			(end -0.7874 0.4064)
			(stroke
				(width 0.1524)
				(type default)
			)
			(layer "F.SilkS")
		)
		(fp_line
			(start -0.67945 -0.305054)
			(end -0.12065 -0.305054)
			(stroke
				(width 0.1)
				(type default)
			)
			(layer "F.Fab")
		)
		(fp_line
			(start -0.67945 0.3048)
			(end -0.67945 -0.305054)
			(stroke
				(width 0.1)
				(type default)
			)
			(layer "F.Fab")
		)
		(fp_line
			(start -0.12065 -0.305054)
			(end -0.12065 -0.2794)
			(stroke
				(width 0.1)
				(type default)
			)
			(layer "F.Fab")
		)
		(fp_line
			(start -0.12065 -0.2794)
			(end 0.12065 -0.2794)
			(stroke
				(width 0.1)
				(type default)
			)
			(layer "F.Fab")
		)
		(fp_line
			(start -0.12065 0.2794)
			(end -0.12065 0.3048)
			(stroke
				(width 0.1)
				(type default)
			)
			(layer "F.Fab")
		)
		(fp_line
			(start -0.12065 0.3048)
			(end -0.67945 0.3048)
			(stroke
				(width 0.1)
				(type default)
			)
			(layer "F.Fab")
		)
		(fp_line
			(start 0.120396 0.2794)
			(end -0.12065 0.2794)
			(stroke
				(width 0.1)
				(type default)
			)
			(layer "F.Fab")
		)
		(fp_line
			(start 0.120396 0.3048)
			(end 0.120396 0.2794)
			(stroke
				(width 0.1)
				(type default)
			)
			(layer "F.Fab")
		)
		(fp_line
			(start 0.12065 -0.3048)
			(end 0.67945 -0.3048)
			(stroke
				(width 0.1)
				(type default)
			)
			(layer "F.Fab")
		)
		(fp_line
			(start 0.12065 -0.2794)
			(end 0.12065 -0.3048)
			(stroke
				(width 0.1)
				(type default)
			)
			(layer "F.Fab")
		)
		(fp_line
			(start 0.67945 -0.3048)
			(end 0.67945 0.3048)
			(stroke
				(width 0.1)
				(type default)
			)
			(layer "F.Fab")
		)
		(fp_line
			(start 0.67945 0.3048)
			(end 0.120396 0.3048)
			(stroke
				(width 0.1)
				(type default)
			)
			(layer "F.Fab")
		)
		(pad "1" smd circle
			(at -0.40005 0)
			(size 0 0)
			(layers "F.Cu" "F.Mask" "F.Paste")
			(net "PVCCIN_CPU0_VCC")
		)
		(pad "2" smd circle
			(at 0.40005 0)
			(size 0 0)
			(layers "F.Cu" "F.Mask" "F.Paste")
			(net "GND")
		)
	)
	(footprint ""
		(layer "F.Cu")
		(at 213.41588 -125.821948)
		(property "Reference" "C1317"
			(at 0 0 0)
			(layer "F.SilkS")
			(hide yes)
			(effects
				(font
					(size 1.27 1.27)
				)
			)
		)
		(property "Value" ""
			(at 0 0 0)
			(layer "F.Fab")
			(effects
				(font
					(size 1.27 1.27)
				)
			)
		)
		(duplicate_pad_numbers_are_jumpers no)
		(fp_line
			(start -0.7874 -0.4064)
			(end 0.7874 -0.4064)
			(stroke
				(width 0.1524)
				(type default)
			)
			(layer "F.SilkS")
		)
		(fp_line
			(start -0.7874 0.4064)
			(end -0.7874 -0.4064)
			(stroke
				(width 0.1524)
				(type default)
			)
			(layer "F.SilkS")
		)
		(fp_line
			(start 0.7874 -0.4064)
			(end 0.7874 0.4064)
			(stroke
				(width 0.1524)
				(type default)
			)
			(layer "F.SilkS")
		)
		(fp_line
			(start 0.7874 0.4064)
			(end -0.7874 0.4064)
			(stroke
				(width 0.1524)
				(type default)
			)
			(layer "F.SilkS")
		)
		(fp_line
			(start -0.67945 -0.305054)
			(end -0.12065 -0.305054)
			(stroke
				(width 0.1)
				(type default)
			)
			(layer "F.Fab")
		)
		(fp_line
			(start -0.67945 0.3048)
			(end -0.67945 -0.305054)
			(stroke
				(width 0.1)
				(type default)
			)
			(layer "F.Fab")
		)
		(fp_line
			(start -0.12065 -0.305054)
			(end -0.12065 -0.2794)
			(stroke
				(width 0.1)
				(type default)
			)
			(layer "F.Fab")
		)
		(fp_line
			(start -0.12065 -0.2794)
			(end 0.12065 -0.2794)
			(stroke
				(width 0.1)
				(type default)
			)
			(layer "F.Fab")
		)
		(fp_line
			(start -0.12065 0.2794)
			(end -0.12065 0.3048)
			(stroke
				(width 0.1)
				(type default)
			)
			(layer "F.Fab")
		)
		(fp_line
			(start -0.12065 0.3048)
			(end -0.67945 0.3048)
			(stroke
				(width 0.1)
				(type default)
			)
			(layer "F.Fab")
		)
		(fp_line
			(start 0.120396 0.2794)
			(end -0.12065 0.2794)
			(stroke
				(width 0.1)
				(type default)
			)
			(layer "F.Fab")
		)
		(fp_line
			(start 0.120396 0.3048)
			(end 0.120396 0.2794)
			(stroke
				(width 0.1)
				(type default)
			)
			(layer "F.Fab")
		)
		(fp_line
			(start 0.12065 -0.3048)
			(end 0.67945 -0.3048)
			(stroke
				(width 0.1)
				(type default)
			)
			(layer "F.Fab")
		)
		(fp_line
			(start 0.12065 -0.2794)
			(end 0.12065 -0.3048)
			(stroke
				(width 0.1)
				(type default)
			)
			(layer "F.Fab")
		)
		(fp_line
			(start 0.67945 -0.3048)
			(end 0.67945 0.3048)
			(stroke
				(width 0.1)
				(type default)
			)
			(layer "F.Fab")
		)
		(fp_line
			(start 0.67945 0.3048)
			(end 0.120396 0.3048)
			(stroke
				(width 0.1)
				(type default)
			)
			(layer "F.Fab")
		)
		(pad "1" smd circle
			(at -0.40005 0)
			(size 0 0)
			(layers "F.Cu" "F.Mask" "F.Paste")
			(net "P3V3_AUX")
		)
		(pad "2" smd circle
			(at 0.40005 0)
			(size 0 0)
			(layers "F.Cu" "F.Mask" "F.Paste")
			(net "GND")
		)
	)
)
